(kicad_pcb
	(version 20260206)
	(generator "pcbnew")
	(generator_version "10.0")
	(general
		(thickness 1.6)
		(legacy_teardrops no)
	)
	(paper "A4")
	(title_block
		(title "12092022_DA0F0TFB6D0_F0T_FAN_BOARD_MP5048_D_brd_v02_OCP.brd")
		(comment 1 "Grand Teton / footprints 185-190 of 924")
	)
	(layers
		(0 "F.Cu" signal "TOP")
		(4 "In1.Cu" signal "GND")
		(6 "In2.Cu" signal "IN1")
		(8 "In3.Cu" signal "IN2")
		(10 "In4.Cu" signal "GND1")
		(2 "B.Cu" signal "BOTTOM")
		(9 "F.Adhes" user "F.Adhesive")
		(11 "B.Adhes" user "B.Adhesive")
		(13 "F.Paste" user "Package Geometry/Pastemask Top")
		(15 "B.Paste" user "Package Geometry/Pastemask Bottom")
		(5 "F.SilkS" user "Ref Des/Silkscreen Top")
		(7 "B.SilkS" user "Ref Des/Silkscreen Bottom")
		(1 "F.Mask" user "Board Geometry/Soldermask Top")
		(3 "B.Mask" user "Board Geometry/Soldermask Bottom")
		(17 "Dwgs.User" user "User.Drawings")
		(19 "Cmts.User" user "User.Comments")
		(21 "Eco1.User" user "User.Eco1")
		(23 "Eco2.User" user "User.Eco2")
		(25 "Edge.Cuts" user "Board Geometry/Outline")
		(27 "Margin" user)
		(31 "F.CrtYd" user "Package Geometry/Place Bound Top")
		(29 "B.CrtYd" user "Package Geometry/Place Bound Bottom")
		(35 "F.Fab" user "Ref Des/Assembly Top")
		(33 "B.Fab" user "Ref Des/Assembly Bottom")
	)
	(footprint ""
		(layer "F.Cu")
		(at 28.829 -121.92 90)
		(property "Reference" "R4940"
			(at 0 0 90)
			(layer "F.SilkS")
			(hide yes)
			(effects
				(font
					(size 1.27 1.27)
				)
			)
		)
		(property "Value" ""
			(at 0 0 90)
			(layer "F.Fab")
			(effects
				(font
					(size 1.27 1.27)
				)
			)
		)
		(duplicate_pad_numbers_are_jumpers no)
		(fp_line
			(start 0.7874 -0.4064)
			(end 0.7874 0.4064)
			(stroke
				(width 0.1524)
				(type default)
			)
			(layer "F.SilkS")
		)
		(fp_line
			(start -0.7874 -0.4064)
			(end 0.7874 -0.4064)
			(stroke
				(width 0.1524)
				(type default)
			)
			(layer "F.SilkS")
		)
		(fp_line
			(start 0.7874 0.4064)
			(end -0.7874 0.4064)
			(stroke
				(width 0.1524)
				(type default)
			)
			(layer "F.SilkS")
		)
		(fp_line
			(start -0.7874 0.4064)
			(end -0.7874 -0.4064)
			(stroke
				(width 0.1524)
				(type default)
			)
			(layer "F.SilkS")
		)
		(fp_line
			(start -0.12065 -0.305054)
			(end -0.12065 -0.2794)
			(stroke
				(width 0.1)
				(type default)
			)
			(layer "F.Fab")
		)
		(fp_line
			(start -0.67945 -0.305054)
			(end -0.12065 -0.305054)
			(stroke
				(width 0.1)
				(type default)
			)
			(layer "F.Fab")
		)
		(fp_line
			(start 0.67945 -0.3048)
			(end 0.67945 0.3048)
			(stroke
				(width 0.1)
				(type default)
			)
			(layer "F.Fab")
		)
		(fp_line
			(start 0.12065 -0.3048)
			(end 0.67945 -0.3048)
			(stroke
				(width 0.1)
				(type default)
			)
			(layer "F.Fab")
		)
		(fp_line
			(start 0.12065 -0.2794)
			(end 0.12065 -0.3048)
			(stroke
				(width 0.1)
				(type default)
			)
			(layer "F.Fab")
		)
		(fp_line
			(start -0.12065 -0.2794)
			(end 0.12065 -0.2794)
			(stroke
				(width 0.1)
				(type default)
			)
			(layer "F.Fab")
		)
		(fp_line
			(start 0.120396 0.2794)
			(end -0.12065 0.2794)
			(stroke
				(width 0.1)
				(type default)
			)
			(layer "F.Fab")
		)
		(fp_line
			(start -0.12065 0.2794)
			(end -0.12065 0.3048)
			(stroke
				(width 0.1)
				(type default)
			)
			(layer "F.Fab")
		)
		(fp_line
			(start 0.67945 0.3048)
			(end 0.120396 0.3048)
			(stroke
				(width 0.1)
				(type default)
			)
			(layer "F.Fab")
		)
		(fp_line
			(start 0.120396 0.3048)
			(end 0.120396 0.2794)
			(stroke
				(width 0.1)
				(type default)
			)
			(layer "F.Fab")
		)
		(fp_line
			(start -0.12065 0.3048)
			(end -0.67945 0.3048)
			(stroke
				(width 0.1)
				(type default)
			)
			(layer "F.Fab")
		)
		(fp_line
			(start -0.67945 0.3048)
			(end -0.67945 -0.305054)
			(stroke
				(width 0.1)
				(type default)
			)
			(layer "F.Fab")
		)
		(pad "1" smd circle
			(at -0.40005 0 90)
			(size 0 0)
			(layers "F.Cu" "F.Mask" "F.Paste")
			(net "GND")
		)
		(pad "2" smd circle
			(at 0.40005 0 90)
			(size 0 0)
			(layers "F.Cu" "F.Mask" "F.Paste")
			(net "MAX31790_U317_FREQ_START")
		)
	)
	(footprint ""
		(layer "F.Cu")
		(at 15.001494 -256.667)
		(property "Reference" "R5424"
			(at 0 0 0)
			(layer "F.SilkS")
			(hide yes)
			(effects
				(font
					(size 1.27 1.27)
				)
			)
		)
		(property "Value" ""
			(at 0 0 0)
			(layer "F.Fab")
			(effects
				(font
					(size 1.27 1.27)
				)
			)
		)
		(duplicate_pad_numbers_are_jumpers no)
		(fp_line
			(start -0.7874 -0.4064)
			(end 0.7874 -0.4064)
			(stroke
				(width 0.1524)
				(type default)
			)
			(layer "F.SilkS")
		)
		(fp_line
			(start -0.7874 0.4064)
			(end -0.7874 -0.4064)
			(stroke
				(width 0.1524)
				(type default)
			)
			(layer "F.SilkS")
		)
		(fp_line
			(start 0.7874 -0.4064)
			(end 0.7874 0.4064)
			(stroke
				(width 0.1524)
				(type default)
			)
			(layer "F.SilkS")
		)
		(fp_line
			(start 0.7874 0.4064)
			(end -0.7874 0.4064)
			(stroke
				(width 0.1524)
				(type default)
			)
			(layer "F.SilkS")
		)
		(fp_line
			(start -0.67945 -0.305054)
			(end -0.12065 -0.305054)
			(stroke
				(width 0.1)
				(type default)
			)
			(layer "F.Fab")
		)
		(fp_line
			(start -0.67945 0.3048)
			(end -0.67945 -0.305054)
			(stroke
				(width 0.1)
				(type default)
			)
			(layer "F.Fab")
		)
		(fp_line
			(start -0.12065 -0.305054)
			(end -0.12065 -0.2794)
			(stroke
				(width 0.1)
				(type default)
			)
			(layer "F.Fab")
		)
		(fp_line
			(start -0.12065 -0.2794)
			(end 0.12065 -0.2794)
			(stroke
				(width 0.1)
				(type default)
			)
			(layer "F.Fab")
		)
		(fp_line
			(start -0.12065 0.2794)
			(end -0.12065 0.3048)
			(stroke
				(width 0.1)
				(type default)
			)
			(layer "F.Fab")
		)
		(fp_line
			(start -0.12065 0.3048)
			(end -0.67945 0.3048)
			(stroke
				(width 0.1)
				(type default)
			)
			(layer "F.Fab")
		)
		(fp_line
			(start 0.120396 0.2794)
			(end -0.12065 0.2794)
			(stroke
				(width 0.1)
				(type default)
			)
			(layer "F.Fab")
		)
		(fp_line
			(start 0.120396 0.3048)
			(end 0.120396 0.2794)
			(stroke
				(width 0.1)
				(type default)
			)
			(layer "F.Fab")
		)
		(fp_line
			(start 0.12065 -0.3048)
			(end 0.67945 -0.3048)
			(stroke
				(width 0.1)
				(type default)
			)
			(layer "F.Fab")
		)
		(fp_line
			(start 0.12065 -0.2794)
			(end 0.12065 -0.3048)
			(stroke
				(width 0.1)
				(type default)
			)
			(layer "F.Fab")
		)
		(fp_line
			(start 0.67945 -0.3048)
			(end 0.67945 0.3048)
			(stroke
				(width 0.1)
				(type default)
			)
			(layer "F.Fab")
		)
		(fp_line
			(start 0.67945 0.3048)
			(end 0.120396 0.3048)
			(stroke
				(width 0.1)
				(type default)
			)
			(layer "F.Fab")
		)
		(pad "1" smd circle
			(at -0.40005 0)
			(size 0 0)
			(layers "F.Cu" "F.Mask" "F.Paste")
			(net "FAN_7_PRESENT_R")
		)
		(pad "2" smd circle
			(at 0.40005 0)
			(size 0 0)
			(layers "F.Cu" "F.Mask" "F.Paste")
			(net "FAN_7_PRESENT")
		)
	)
	(footprint ""
		(layer "F.Cu")
		(at 14.732 -258.064 180)
		(property "Reference" "PR71"
			(at 0 0 180)
			(layer "F.SilkS")
			(hide yes)
			(effects
				(font
					(size 1.27 1.27)
				)
			)
		)
		(property "Value" ""
			(at 0 0 180)
			(layer "F.Fab")
			(effects
				(font
					(size 1.27 1.27)
				)
			)
		)
		(duplicate_pad_numbers_are_jumpers no)
		(fp_line
			(start 0.7874 0.4064)
			(end -0.7874 0.4064)
			(stroke
				(width 0.1524)
				(type default)
			)
			(layer "F.SilkS")
		)
		(fp_line
			(start 0.7874 -0.4064)
			(end 0.7874 0.4064)
			(stroke
				(width 0.1524)
				(type default)
			)
			(layer "F.SilkS")
		)
		(fp_line
			(start -0.7874 0.4064)
			(end -0.7874 -0.4064)
			(stroke
				(width 0.1524)
				(type default)
			)
			(layer "F.SilkS")
		)
		(fp_line
			(start -0.7874 -0.4064)
			(end 0.7874 -0.4064)
			(stroke
				(width 0.1524)
				(type default)
			)
			(layer "F.SilkS")
		)
		(fp_line
			(start 0.67945 0.3048)
			(end 0.120396 0.3048)
			(stroke
				(width 0.1)
				(type default)
			)
			(layer "F.Fab")
		)
		(fp_line
			(start 0.67945 -0.3048)
			(end 0.67945 0.3048)
			(stroke
				(width 0.1)
				(type default)
			)
			(layer "F.Fab")
		)
		(fp_line
			(start 0.12065 -0.2794)
			(end 0.12065 -0.3048)
			(stroke
				(width 0.1)
				(type default)
			)
			(layer "F.Fab")
		)
		(fp_line
			(start 0.12065 -0.3048)
			(end 0.67945 -0.3048)
			(stroke
				(width 0.1)
				(type default)
			)
			(layer "F.Fab")
		)
		(fp_line
			(start 0.120396 0.3048)
			(end 0.120396 0.2794)
			(stroke
				(width 0.1)
				(type default)
			)
			(layer "F.Fab")
		)
		(fp_line
			(start 0.120396 0.2794)
			(end -0.12065 0.2794)
			(stroke
				(width 0.1)
				(type default)
			)
			(layer "F.Fab")
		)
		(fp_line
			(start -0.12065 0.3048)
			(end -0.67945 0.3048)
			(stroke
				(width 0.1)
				(type default)
			)
			(layer "F.Fab")
		)
		(fp_line
			(start -0.12065 0.2794)
			(end -0.12065 0.3048)
			(stroke
				(width 0.1)
				(type default)
			)
			(layer "F.Fab")
		)
		(fp_line
			(start -0.12065 -0.2794)
			(end 0.12065 -0.2794)
			(stroke
				(width 0.1)
				(type default)
			)
			(layer "F.Fab")
		)
		(fp_line
			(start -0.12065 -0.305054)
			(end -0.12065 -0.2794)
			(stroke
				(width 0.1)
				(type default)
			)
			(layer "F.Fab")
		)
		(fp_line
			(start -0.67945 0.3048)
			(end -0.67945 -0.305054)
			(stroke
				(width 0.1)
				(type default)
			)
			(layer "F.Fab")
		)
		(fp_line
			(start -0.67945 -0.305054)
			(end -0.12065 -0.305054)
			(stroke
				(width 0.1)
				(type default)
			)
			(layer "F.Fab")
		)
		(pad "1" smd circle
			(at -0.40005 0 180)
			(size 0 0)
			(layers "F.Cu" "F.Mask" "F.Paste")
			(net "FAN_7_FAULT_R")
		)
		(pad "2" smd circle
			(at 0.40005 0 180)
			(size 0 0)
			(layers "F.Cu" "F.Mask" "F.Paste")
			(net "FAN_7_P3V_R")
		)
	)
	(footprint ""
		(layer "F.Cu")
		(at 8.709914 -251.587 180)
		(property "Reference" "C2070"
			(at 0 0 180)
			(layer "F.SilkS")
			(hide yes)
			(effects
				(font
					(size 1.27 1.27)
				)
			)
		)
		(property "Value" ""
			(at 0 0 180)
			(layer "F.Fab")
			(effects
				(font
					(size 1.27 1.27)
				)
			)
		)
		(duplicate_pad_numbers_are_jumpers no)
		(fp_line
			(start 0.7874 0.4064)
			(end -0.7874 0.4064)
			(stroke
				(width 0.1524)
				(type default)
			)
			(layer "F.SilkS")
		)
		(fp_line
			(start 0.7874 -0.4064)
			(end 0.7874 0.4064)
			(stroke
				(width 0.1524)
				(type default)
			)
			(layer "F.SilkS")
		)
		(fp_line
			(start -0.7874 0.4064)
			(end -0.7874 -0.4064)
			(stroke
				(width 0.1524)
				(type default)
			)
			(layer "F.SilkS")
		)
		(fp_line
			(start -0.7874 -0.4064)
			(end 0.7874 -0.4064)
			(stroke
				(width 0.1524)
				(type default)
			)
			(layer "F.SilkS")
		)
		(fp_line
			(start 0.67945 0.3048)
			(end 0.120396 0.3048)
			(stroke
				(width 0.1)
				(type default)
			)
			(layer "F.Fab")
		)
		(fp_line
			(start 0.67945 -0.3048)
			(end 0.67945 0.3048)
			(stroke
				(width 0.1)
				(type default)
			)
			(layer "F.Fab")
		)
		(fp_line
			(start 0.12065 -0.2794)
			(end 0.12065 -0.3048)
			(stroke
				(width 0.1)
				(type default)
			)
			(layer "F.Fab")
		)
		(fp_line
			(start 0.12065 -0.3048)
			(end 0.67945 -0.3048)
			(stroke
				(width 0.1)
				(type default)
			)
			(layer "F.Fab")
		)
		(fp_line
			(start 0.120396 0.3048)
			(end 0.120396 0.2794)
			(stroke
				(width 0.1)
				(type default)
			)
			(layer "F.Fab")
		)
		(fp_line
			(start 0.120396 0.2794)
			(end -0.12065 0.2794)
			(stroke
				(width 0.1)
				(type default)
			)
			(layer "F.Fab")
		)
		(fp_line
			(start -0.12065 0.3048)
			(end -0.67945 0.3048)
			(stroke
				(width 0.1)
				(type default)
			)
			(layer "F.Fab")
		)
		(fp_line
			(start -0.12065 0.2794)
			(end -0.12065 0.3048)
			(stroke
				(width 0.1)
				(type default)
			)
			(layer "F.Fab")
		)
		(fp_line
			(start -0.12065 -0.2794)
			(end 0.12065 -0.2794)
			(stroke
				(width 0.1)
				(type default)
			)
			(layer "F.Fab")
		)
		(fp_line
			(start -0.12065 -0.305054)
			(end -0.12065 -0.2794)
			(stroke
				(width 0.1)
				(type default)
			)
			(layer "F.Fab")
		)
		(fp_line
			(start -0.67945 0.3048)
			(end -0.67945 -0.305054)
			(stroke
				(width 0.1)
				(type default)
			)
			(layer "F.Fab")
		)
		(fp_line
			(start -0.67945 -0.305054)
			(end -0.12065 -0.305054)
			(stroke
				(width 0.1)
				(type default)
			)
			(layer "F.Fab")
		)
		(pad "1" smd circle
			(at -0.40005 0 180)
			(size 0 0)
			(layers "F.Cu" "F.Mask" "F.Paste")
			(net "P3V3_AUX")
		)
		(pad "2" smd circle
			(at 0.40005 0 180)
			(size 0 0)
			(layers "F.Cu" "F.Mask" "F.Paste")
			(net "GND")
		)
	)
	(footprint ""
		(layer "F.Cu")
		(at 37.338 -23.876)
		(property "Reference" "D281"
			(at 1.143 -0.73533 0)
			(unlocked yes)
			(layer "F.SilkS")
			(effects
				(font
					(size 0.7874 0.5842)
					(thickness 0.1524)
				)
				(justify left)
			)
		)
		(property "Value" ""
			(at 0 0 0)
			(layer "F.Fab")
			(effects
				(font
					(size 1.27 1.27)
				)
			)
		)
		(duplicate_pad_numbers_are_jumpers no)
		(fp_line
			(start -0.854964 -0.450088)
			(end -0.854964 0.450088)
			(stroke
				(width 0.1524)
				(type default)
			)
			(layer "F.SilkS")
		)
		(fp_line
			(start -0.854964 0.450088)
			(end 0.925068 0.450088)
			(stroke
				(width 0.1524)
				(type default)
			)
			(layer "F.SilkS")
		)
		(fp_line
			(start 0.845058 0.4064)
			(end 0.845058 -0.381)
			(stroke
				(width 0.1524)
				(type default)
			)
			(layer "F.SilkS")
		)
		(fp_line
			(start 0.870458 -0.2794)
			(end 0.845058 0.4064)
			(stroke
				(width 0.1524)
				(type default)
			)
			(layer "F.SilkS")
		)
		(fp_line
			(start 0.94488 -0.450088)
			(end -0.854964 -0.450088)
			(stroke
				(width 0.1524)
				(type default)
			)
			(layer "F.SilkS")
		)
		(fp_line
			(start 0.94488 0.450088)
			(end 0.94488 -0.450088)
			(stroke
				(width 0.1524)
				(type default)
			)
			(layer "F.SilkS")
		)
		(fp_line
			(start -0.54991 -0.350012)
			(end -0.54991 0.350012)
			(stroke
				(width 0.1)
				(type default)
			)
			(layer "F.Fab")
		)
		(fp_line
			(start -0.54991 0.350012)
			(end 0.54991 0.350012)
			(stroke
				(width 0.1)
				(type default)
			)
			(layer "F.Fab")
		)
		(fp_line
			(start 0.54991 -0.350012)
			(end -0.54991 -0.350012)
			(stroke
				(width 0.1)
				(type default)
			)
			(layer "F.Fab")
		)
		(fp_line
			(start 0.54991 0.350012)
			(end 0.54991 -0.350012)
			(stroke
				(width 0.1)
				(type default)
			)
			(layer "F.Fab")
		)
		(fp_text user "+"
			(at -0.635 0.09525 180)
			(unlocked yes)
			(layer "F.SilkS")
			(effects
				(font
					(size 1.905 1.4224)
					(thickness 0.1524)
				)
				(justify left)
			)
		)
		(fp_text user "-"
			(at 2.159 0.09525 180)
			(unlocked yes)
			(layer "F.SilkS")
			(effects
				(font
					(size 1.905 1.4224)
					(thickness 0.1524)
				)
				(justify left)
			)
		)
		(fp_text user "+"
			(at -0.808228 0.239014 180)
			(unlocked yes)
			(layer "F.Fab")
			(effects
				(font
					(size 1.905 1.4224)
					(thickness 0.1524)
				)
				(justify left)
			)
		)
		(fp_text user "-"
			(at 2.48539 0.239014 180)
			(unlocked yes)
			(layer "F.Fab")
			(effects
				(font
					(size 1.905 1.4224)
					(thickness 0.1524)
				)
				(justify left)
			)
		)
		(pad "A" smd rect
			(at -0.424942 0)
			(size 0.5588 0.6096)
			(layers "F.Cu" "F.Mask" "F.Paste")
			(net "GND")
		)
		(pad "C" smd rect
			(at 0.424942 0 180)
			(size 0.5588 0.6096)
			(layers "F.Cu" "F.Mask" "F.Paste")
			(net "FAN_3_FAIL_R_LED_N")
		)
	)
	(footprint ""
		(layer "F.Cu")
		(at 39.206932 -255.143 180)
		(property "Reference" "R5417"
			(at 0 0 180)
			(layer "F.SilkS")
			(hide yes)
			(effects
				(font
					(size 1.27 1.27)
				)
			)
		)
		(property "Value" ""
			(at 0 0 180)
			(layer "F.Fab")
			(effects
				(font
					(size 1.27 1.27)
				)
			)
		)
		(duplicate_pad_numbers_are_jumpers no)
		(fp_line
			(start 0.7874 0.4064)
			(end -0.7874 0.4064)
			(stroke
				(width 0.1524)
				(type default)
			)
			(layer "F.SilkS")
		)
		(fp_line
			(start 0.7874 -0.4064)
			(end 0.7874 0.4064)
			(stroke
				(width 0.1524)
				(type default)
			)
			(layer "F.SilkS")
		)
		(fp_line
			(start -0.7874 0.4064)
			(end -0.7874 -0.4064)
			(stroke
				(width 0.1524)
				(type default)
			)
			(layer "F.SilkS")
		)
		(fp_line
			(start -0.7874 -0.4064)
			(end 0.7874 -0.4064)
			(stroke
				(width 0.1524)
				(type default)
			)
			(layer "F.SilkS")
		)
		(fp_line
			(start 0.67945 0.3048)
			(end 0.120396 0.3048)
			(stroke
				(width 0.1)
				(type default)
			)
			(layer "F.Fab")
		)
		(fp_line
			(start 0.67945 -0.3048)
			(end 0.67945 0.3048)
			(stroke
				(width 0.1)
				(type default)
			)
			(layer "F.Fab")
		)
		(fp_line
			(start 0.12065 -0.2794)
			(end 0.12065 -0.3048)
			(stroke
				(width 0.1)
				(type default)
			)
			(layer "F.Fab")
		)
		(fp_line
			(start 0.12065 -0.3048)
			(end 0.67945 -0.3048)
			(stroke
				(width 0.1)
				(type default)
			)
			(layer "F.Fab")
		)
		(fp_line
			(start 0.120396 0.3048)
			(end 0.120396 0.2794)
			(stroke
				(width 0.1)
				(type default)
			)
			(layer "F.Fab")
		)
		(fp_line
			(start 0.120396 0.2794)
			(end -0.12065 0.2794)
			(stroke
				(width 0.1)
				(type default)
			)
			(layer "F.Fab")
		)
		(fp_line
			(start -0.12065 0.3048)
			(end -0.67945 0.3048)
			(stroke
				(width 0.1)
				(type default)
			)
			(layer "F.Fab")
		)
		(fp_line
			(start -0.12065 0.2794)
			(end -0.12065 0.3048)
			(stroke
				(width 0.1)
				(type default)
			)
			(layer "F.Fab")
		)
		(fp_line
			(start -0.12065 -0.2794)
			(end 0.12065 -0.2794)
			(stroke
				(width 0.1)
				(type default)
			)
			(layer "F.Fab")
		)
		(fp_line
			(start -0.12065 -0.305054)
			(end -0.12065 -0.2794)
			(stroke
				(width 0.1)
				(type default)
			)
			(layer "F.Fab")
		)
		(fp_line
			(start -0.67945 0.3048)
			(end -0.67945 -0.305054)
			(stroke
				(width 0.1)
				(type default)
			)
			(layer "F.Fab")
		)
		(fp_line
			(start -0.67945 -0.305054)
			(end -0.12065 -0.305054)
			(stroke
				(width 0.1)
				(type default)
			)
			(layer "F.Fab")
		)
		(pad "1" smd circle
			(at -0.40005 0 180)
			(size 0 0)
			(layers "F.Cu" "F.Mask" "F.Paste")
			(net "FAN_0_ON")
		)
		(pad "2" smd circle
			(at 0.40005 0 180)
			(size 0 0)
			(layers "F.Cu" "F.Mask" "F.Paste")
			(net "P52V_FAN_0_EN")
		)
	)
)
